(kicad_pcb
	(version 20260206)
	(generator "pcbnew")
	(generator_version "10.0")
	(general
		(thickness 1.6)
		(legacy_teardrops no)
	)
	(paper "A4")
	(title_block
		(title "03242023_DA0F0TMBIJ0_F0T_Motherboard_J_brd_V01_OCP.brd")
		(comment 1 "Grand Teton / footprints 4092-4098 of 6105")
	)
	(layers
		(0 "F.Cu" signal "TOP")
		(4 "In1.Cu" signal "GND")
		(6 "In2.Cu" signal "IN1")
		(8 "In3.Cu" signal "GND1")
		(10 "In4.Cu" signal "IN2")
		(12 "In5.Cu" signal "GND2")
		(14 "In6.Cu" signal "IN3")
		(16 "In7.Cu" signal "GND3")
		(18 "In8.Cu" signal "VCC")
		(20 "In9.Cu" signal "VCC1")
		(22 "In10.Cu" signal "GND4")
		(24 "In11.Cu" signal "IN4")
		(26 "In12.Cu" signal "GND5")
		(28 "In13.Cu" signal "IN5")
		(30 "In14.Cu" signal "GND6")
		(32 "In15.Cu" signal "IN6")
		(34 "In16.Cu" signal "GND7")
		(2 "B.Cu" signal "BOTTOM")
		(9 "F.Adhes" user "F.Adhesive")
		(11 "B.Adhes" user "B.Adhesive")
		(13 "F.Paste" user "Package Geometry/Pastemask Top")
		(15 "B.Paste" user "Package Geometry/Pastemask Bottom")
		(5 "F.SilkS" user "Ref Des/Silkscreen Top")
		(7 "B.SilkS" user "Ref Des/Silkscreen Bottom")
		(1 "F.Mask" user "Board Geometry/Soldermask Top")
		(3 "B.Mask" user "Board Geometry/Soldermask Bottom")
		(17 "Dwgs.User" user "User.Drawings")
		(19 "Cmts.User" user "User.Comments")
		(21 "Eco1.User" user "User.Eco1")
		(23 "Eco2.User" user "User.Eco2")
		(25 "Edge.Cuts" user "Board Geometry/Outline")
		(27 "Margin" user)
		(31 "F.CrtYd" user "Package Geometry/Place Bound Top")
		(29 "B.CrtYd" user "Package Geometry/Place Bound Bottom")
		(35 "F.Fab" user "Ref Des/Assembly Top")
		(33 "B.Fab" user "Ref Des/Assembly Bottom")
	)
	(footprint ""
		(layer "F.Cu")
		(at 319.668906 -26.651458 -90)
		(property "Reference" "R139"
			(at 0 0 270)
			(layer "F.SilkS")
			(hide yes)
			(effects
				(font
					(size 1.27 1.27)
				)
			)
		)
		(property "Value" ""
			(at 0 0 270)
			(layer "F.Fab")
			(effects
				(font
					(size 1.27 1.27)
				)
			)
		)
		(duplicate_pad_numbers_are_jumpers no)
		(fp_line
			(start -0.7874 0.4064)
			(end -0.7874 -0.4064)
			(stroke
				(width 0.1524)
				(type default)
			)
			(layer "F.SilkS")
		)
		(fp_line
			(start 0.7874 0.4064)
			(end -0.7874 0.4064)
			(stroke
				(width 0.1524)
				(type default)
			)
			(layer "F.SilkS")
		)
		(fp_line
			(start -0.7874 -0.4064)
			(end 0.7874 -0.4064)
			(stroke
				(width 0.1524)
				(type default)
			)
			(layer "F.SilkS")
		)
		(fp_line
			(start 0.7874 -0.4064)
			(end 0.7874 0.4064)
			(stroke
				(width 0.1524)
				(type default)
			)
			(layer "F.SilkS")
		)
		(fp_line
			(start -0.67945 0.3048)
			(end -0.67945 -0.305054)
			(stroke
				(width 0.1)
				(type default)
			)
			(layer "F.Fab")
		)
		(fp_line
			(start -0.12065 0.3048)
			(end -0.67945 0.3048)
			(stroke
				(width 0.1)
				(type default)
			)
			(layer "F.Fab")
		)
		(fp_line
			(start 0.120396 0.3048)
			(end 0.120396 0.2794)
			(stroke
				(width 0.1)
				(type default)
			)
			(layer "F.Fab")
		)
		(fp_line
			(start 0.67945 0.3048)
			(end 0.120396 0.3048)
			(stroke
				(width 0.1)
				(type default)
			)
			(layer "F.Fab")
		)
		(fp_line
			(start -0.12065 0.2794)
			(end -0.12065 0.3048)
			(stroke
				(width 0.1)
				(type default)
			)
			(layer "F.Fab")
		)
		(fp_line
			(start 0.120396 0.2794)
			(end -0.12065 0.2794)
			(stroke
				(width 0.1)
				(type default)
			)
			(layer "F.Fab")
		)
		(fp_line
			(start -0.12065 -0.2794)
			(end 0.12065 -0.2794)
			(stroke
				(width 0.1)
				(type default)
			)
			(layer "F.Fab")
		)
		(fp_line
			(start 0.12065 -0.2794)
			(end 0.12065 -0.3048)
			(stroke
				(width 0.1)
				(type default)
			)
			(layer "F.Fab")
		)
		(fp_line
			(start 0.12065 -0.3048)
			(end 0.67945 -0.3048)
			(stroke
				(width 0.1)
				(type default)
			)
			(layer "F.Fab")
		)
		(fp_line
			(start 0.67945 -0.3048)
			(end 0.67945 0.3048)
			(stroke
				(width 0.1)
				(type default)
			)
			(layer "F.Fab")
		)
		(fp_line
			(start -0.67945 -0.305054)
			(end -0.12065 -0.305054)
			(stroke
				(width 0.1)
				(type default)
			)
			(layer "F.Fab")
		)
		(fp_line
			(start -0.12065 -0.305054)
			(end -0.12065 -0.2794)
			(stroke
				(width 0.1)
				(type default)
			)
			(layer "F.Fab")
		)
		(pad "1" smd circle
			(at -0.40005 0 270)
			(size 0 0)
			(layers "F.Cu" "F.Mask" "F.Paste")
			(net "FM_BMC_PWRBTN_N")
		)
		(pad "2" smd circle
			(at 0.40005 0 270)
			(size 0 0)
			(layers "F.Cu" "F.Mask" "F.Paste")
			(net "P3V3_AUX")
		)
	)
	(footprint ""
		(layer "F.Cu")
		(at 103.198676 -79.078836)
		(property "Reference" "D93"
			(at -51.54041 38.649402 90)
			(unlocked yes)
			(layer "F.SilkS")
			(effects
				(font
					(size 0.635 0.4064)
					(thickness 0.1524)
				)
				(justify left)
			)
		)
		(property "Value" ""
			(at 0 0 0)
			(layer "F.Fab")
			(effects
				(font
					(size 1.27 1.27)
				)
			)
		)
		(duplicate_pad_numbers_are_jumpers no)
		(fp_line
			(start -0.90678 0.4826)
			(end -0.90678 -0.4699)
			(stroke
				(width 0.1524)
				(type default)
			)
			(layer "F.SilkS")
		)
		(fp_line
			(start -0.89408 -0.4826)
			(end 0.90678 -0.4826)
			(stroke
				(width 0.1524)
				(type default)
			)
			(layer "F.SilkS")
		)
		(fp_line
			(start -0.79248 -0.4826)
			(end 1.03378 -0.4826)
			(stroke
				(width 0.1524)
				(type default)
			)
			(layer "F.SilkS")
		)
		(fp_line
			(start -0.64008 -0.4826)
			(end 1.16078 -0.4826)
			(stroke
				(width 0.1524)
				(type default)
			)
			(layer "F.SilkS")
		)
		(fp_line
			(start 0.90678 -0.4826)
			(end 0.90678 0.4826)
			(stroke
				(width 0.1524)
				(type default)
			)
			(layer "F.SilkS")
		)
		(fp_line
			(start 0.90678 0.4826)
			(end -0.90678 0.4826)
			(stroke
				(width 0.1524)
				(type default)
			)
			(layer "F.SilkS")
		)
		(fp_line
			(start 1.03378 -0.4826)
			(end 1.03378 0.4826)
			(stroke
				(width 0.1524)
				(type default)
			)
			(layer "F.SilkS")
		)
		(fp_line
			(start 1.03378 0.4826)
			(end -0.79248 0.4826)
			(stroke
				(width 0.1524)
				(type default)
			)
			(layer "F.SilkS")
		)
		(fp_line
			(start 1.16078 -0.4826)
			(end 1.16078 0.4826)
			(stroke
				(width 0.1524)
				(type default)
			)
			(layer "F.SilkS")
		)
		(fp_line
			(start 1.16078 0.4826)
			(end -0.64008 0.4826)
			(stroke
				(width 0.1524)
				(type default)
			)
			(layer "F.SilkS")
		)
		(fp_line
			(start -0.499872 -0.249936)
			(end 0.499872 -0.249936)
			(stroke
				(width 0.1)
				(type default)
			)
			(layer "F.Fab")
		)
		(fp_line
			(start -0.499872 0.249936)
			(end -0.499872 -0.249936)
			(stroke
				(width 0.1)
				(type default)
			)
			(layer "F.Fab")
		)
		(fp_line
			(start 0.499872 -0.249936)
			(end 0.499872 0.249936)
			(stroke
				(width 0.1)
				(type default)
			)
			(layer "F.Fab")
		)
		(fp_line
			(start 0.499872 0.249936)
			(end -0.499872 0.249936)
			(stroke
				(width 0.1)
				(type default)
			)
			(layer "F.Fab")
		)
		(pad "A" smd rect
			(at -0.47498 0)
			(size 0.6096 0.7112)
			(layers "F.Cu" "F.Mask" "F.Paste")
			(net "LED_RST_RSMRST_PLD_R_N")
		)
		(pad "C" smd rect
			(at 0.47498 0)
			(size 0.6096 0.7112)
			(layers "F.Cu" "F.Mask" "F.Paste")
			(net "LED_RST_RSMRST_PLD_R_N_D")
		)
	)
	(footprint ""
		(layer "F.Cu")
		(at 116.13388 -403.35073 90)
		(property "Reference" "R2835"
			(at 0 0 90)
			(layer "F.SilkS")
			(hide yes)
			(effects
				(font
					(size 1.27 1.27)
				)
			)
		)
		(property "Value" ""
			(at 0 0 90)
			(layer "F.Fab")
			(effects
				(font
					(size 1.27 1.27)
				)
			)
		)
		(duplicate_pad_numbers_are_jumpers no)
		(fp_line
			(start 0.7874 -0.4064)
			(end 0.7874 0.4064)
			(stroke
				(width 0.1524)
				(type default)
			)
			(layer "F.SilkS")
		)
		(fp_line
			(start -0.7874 -0.4064)
			(end 0.7874 -0.4064)
			(stroke
				(width 0.1524)
				(type default)
			)
			(layer "F.SilkS")
		)
		(fp_line
			(start 0.7874 0.4064)
			(end -0.7874 0.4064)
			(stroke
				(width 0.1524)
				(type default)
			)
			(layer "F.SilkS")
		)
		(fp_line
			(start -0.7874 0.4064)
			(end -0.7874 -0.4064)
			(stroke
				(width 0.1524)
				(type default)
			)
			(layer "F.SilkS")
		)
		(fp_line
			(start -0.12065 -0.305054)
			(end -0.12065 -0.2794)
			(stroke
				(width 0.1)
				(type default)
			)
			(layer "F.Fab")
		)
		(fp_line
			(start -0.67945 -0.305054)
			(end -0.12065 -0.305054)
			(stroke
				(width 0.1)
				(type default)
			)
			(layer "F.Fab")
		)
		(fp_line
			(start 0.67945 -0.3048)
			(end 0.67945 0.3048)
			(stroke
				(width 0.1)
				(type default)
			)
			(layer "F.Fab")
		)
		(fp_line
			(start 0.12065 -0.3048)
			(end 0.67945 -0.3048)
			(stroke
				(width 0.1)
				(type default)
			)
			(layer "F.Fab")
		)
		(fp_line
			(start 0.12065 -0.2794)
			(end 0.12065 -0.3048)
			(stroke
				(width 0.1)
				(type default)
			)
			(layer "F.Fab")
		)
		(fp_line
			(start -0.12065 -0.2794)
			(end 0.12065 -0.2794)
			(stroke
				(width 0.1)
				(type default)
			)
			(layer "F.Fab")
		)
		(fp_line
			(start 0.120396 0.2794)
			(end -0.12065 0.2794)
			(stroke
				(width 0.1)
				(type default)
			)
			(layer "F.Fab")
		)
		(fp_line
			(start -0.12065 0.2794)
			(end -0.12065 0.3048)
			(stroke
				(width 0.1)
				(type default)
			)
			(layer "F.Fab")
		)
		(fp_line
			(start 0.67945 0.3048)
			(end 0.120396 0.3048)
			(stroke
				(width 0.1)
				(type default)
			)
			(layer "F.Fab")
		)
		(fp_line
			(start 0.120396 0.3048)
			(end 0.120396 0.2794)
			(stroke
				(width 0.1)
				(type default)
			)
			(layer "F.Fab")
		)
		(fp_line
			(start -0.12065 0.3048)
			(end -0.67945 0.3048)
			(stroke
				(width 0.1)
				(type default)
			)
			(layer "F.Fab")
		)
		(fp_line
			(start -0.67945 0.3048)
			(end -0.67945 -0.305054)
			(stroke
				(width 0.1)
				(type default)
			)
			(layer "F.Fab")
		)
		(pad "1" smd circle
			(at -0.40005 0 90)
			(size 0 0)
			(layers "F.Cu" "F.Mask" "F.Paste")
			(net "P3V3_AUX")
		)
		(pad "2" smd circle
			(at 0.40005 0 90)
			(size 0 0)
			(layers "F.Cu" "F.Mask" "F.Paste")
			(net "BIC_MONITER_N")
		)
	)
	(footprint ""
		(layer "F.Cu")
		(at 169.44848 -425.922948 180)
		(property "Reference" "R2915"
			(at 0 0 180)
			(layer "F.SilkS")
			(hide yes)
			(effects
				(font
					(size 1.27 1.27)
				)
			)
		)
		(property "Value" ""
			(at 0 0 180)
			(layer "F.Fab")
			(effects
				(font
					(size 1.27 1.27)
				)
			)
		)
		(duplicate_pad_numbers_are_jumpers no)
		(fp_line
			(start 0.7874 0.4064)
			(end -0.7874 0.4064)
			(stroke
				(width 0.1524)
				(type default)
			)
			(layer "F.SilkS")
		)
		(fp_line
			(start 0.7874 -0.4064)
			(end 0.7874 0.4064)
			(stroke
				(width 0.1524)
				(type default)
			)
			(layer "F.SilkS")
		)
		(fp_line
			(start -0.7874 0.4064)
			(end -0.7874 -0.4064)
			(stroke
				(width 0.1524)
				(type default)
			)
			(layer "F.SilkS")
		)
		(fp_line
			(start -0.7874 -0.4064)
			(end 0.7874 -0.4064)
			(stroke
				(width 0.1524)
				(type default)
			)
			(layer "F.SilkS")
		)
		(fp_line
			(start 0.67945 0.3048)
			(end 0.120396 0.3048)
			(stroke
				(width 0.1)
				(type default)
			)
			(layer "F.Fab")
		)
		(fp_line
			(start 0.67945 -0.3048)
			(end 0.67945 0.3048)
			(stroke
				(width 0.1)
				(type default)
			)
			(layer "F.Fab")
		)
		(fp_line
			(start 0.12065 -0.2794)
			(end 0.12065 -0.3048)
			(stroke
				(width 0.1)
				(type default)
			)
			(layer "F.Fab")
		)
		(fp_line
			(start 0.12065 -0.3048)
			(end 0.67945 -0.3048)
			(stroke
				(width 0.1)
				(type default)
			)
			(layer "F.Fab")
		)
		(fp_line
			(start 0.120396 0.3048)
			(end 0.120396 0.2794)
			(stroke
				(width 0.1)
				(type default)
			)
			(layer "F.Fab")
		)
		(fp_line
			(start 0.120396 0.2794)
			(end -0.12065 0.2794)
			(stroke
				(width 0.1)
				(type default)
			)
			(layer "F.Fab")
		)
		(fp_line
			(start -0.12065 0.3048)
			(end -0.67945 0.3048)
			(stroke
				(width 0.1)
				(type default)
			)
			(layer "F.Fab")
		)
		(fp_line
			(start -0.12065 0.2794)
			(end -0.12065 0.3048)
			(stroke
				(width 0.1)
				(type default)
			)
			(layer "F.Fab")
		)
		(fp_line
			(start -0.12065 -0.2794)
			(end 0.12065 -0.2794)
			(stroke
				(width 0.1)
				(type default)
			)
			(layer "F.Fab")
		)
		(fp_line
			(start -0.12065 -0.305054)
			(end -0.12065 -0.2794)
			(stroke
				(width 0.1)
				(type default)
			)
			(layer "F.Fab")
		)
		(fp_line
			(start -0.67945 0.3048)
			(end -0.67945 -0.305054)
			(stroke
				(width 0.1)
				(type default)
			)
			(layer "F.Fab")
		)
		(fp_line
			(start -0.67945 -0.305054)
			(end -0.12065 -0.305054)
			(stroke
				(width 0.1)
				(type default)
			)
			(layer "F.Fab")
		)
		(pad "1" smd circle
			(at -0.40005 0 180)
			(size 0 0)
			(layers "F.Cu" "F.Mask" "F.Paste")
			(net "BMC_MONITER_R")
		)
		(pad "2" smd circle
			(at 0.40005 0 180)
			(size 0 0)
			(layers "F.Cu" "F.Mask" "F.Paste")
			(net "GND")
		)
	)
	(footprint ""
		(layer "F.Cu")
		(at 224.771712 -67.921378)
		(property "Reference" "R3973"
			(at 0 0 0)
			(layer "F.SilkS")
			(hide yes)
			(effects
				(font
					(size 1.27 1.27)
				)
			)
		)
		(property "Value" ""
			(at 0 0 0)
			(layer "F.Fab")
			(effects
				(font
					(size 1.27 1.27)
				)
			)
		)
		(duplicate_pad_numbers_are_jumpers no)
		(fp_line
			(start -0.7874 -0.4064)
			(end 0.7874 -0.4064)
			(stroke
				(width 0.1524)
				(type default)
			)
			(layer "F.SilkS")
		)
		(fp_line
			(start -0.7874 0.4064)
			(end -0.7874 -0.4064)
			(stroke
				(width 0.1524)
				(type default)
			)
			(layer "F.SilkS")
		)
		(fp_line
			(start 0.7874 -0.4064)
			(end 0.7874 0.4064)
			(stroke
				(width 0.1524)
				(type default)
			)
			(layer "F.SilkS")
		)
		(fp_line
			(start 0.7874 0.4064)
			(end -0.7874 0.4064)
			(stroke
				(width 0.1524)
				(type default)
			)
			(layer "F.SilkS")
		)
		(fp_line
			(start -0.67945 -0.305054)
			(end -0.12065 -0.305054)
			(stroke
				(width 0.1)
				(type default)
			)
			(layer "F.Fab")
		)
		(fp_line
			(start -0.67945 0.3048)
			(end -0.67945 -0.305054)
			(stroke
				(width 0.1)
				(type default)
			)
			(layer "F.Fab")
		)
		(fp_line
			(start -0.12065 -0.305054)
			(end -0.12065 -0.2794)
			(stroke
				(width 0.1)
				(type default)
			)
			(layer "F.Fab")
		)
		(fp_line
			(start -0.12065 -0.2794)
			(end 0.12065 -0.2794)
			(stroke
				(width 0.1)
				(type default)
			)
			(layer "F.Fab")
		)
		(fp_line
			(start -0.12065 0.2794)
			(end -0.12065 0.3048)
			(stroke
				(width 0.1)
				(type default)
			)
			(layer "F.Fab")
		)
		(fp_line
			(start -0.12065 0.3048)
			(end -0.67945 0.3048)
			(stroke
				(width 0.1)
				(type default)
			)
			(layer "F.Fab")
		)
		(fp_line
			(start 0.120396 0.2794)
			(end -0.12065 0.2794)
			(stroke
				(width 0.1)
				(type default)
			)
			(layer "F.Fab")
		)
		(fp_line
			(start 0.120396 0.3048)
			(end 0.120396 0.2794)
			(stroke
				(width 0.1)
				(type default)
			)
			(layer "F.Fab")
		)
		(fp_line
			(start 0.12065 -0.3048)
			(end 0.67945 -0.3048)
			(stroke
				(width 0.1)
				(type default)
			)
			(layer "F.Fab")
		)
		(fp_line
			(start 0.12065 -0.2794)
			(end 0.12065 -0.3048)
			(stroke
				(width 0.1)
				(type default)
			)
			(layer "F.Fab")
		)
		(fp_line
			(start 0.67945 -0.3048)
			(end 0.67945 0.3048)
			(stroke
				(width 0.1)
				(type default)
			)
			(layer "F.Fab")
		)
		(fp_line
			(start 0.67945 0.3048)
			(end 0.120396 0.3048)
			(stroke
				(width 0.1)
				(type default)
			)
			(layer "F.Fab")
		)
		(pad "1" smd circle
			(at -0.40005 0)
			(size 0 0)
			(layers "F.Cu" "F.Mask" "F.Paste")
			(net "P3V3_E1S_PWRGD_0")
		)
		(pad "2" smd circle
			(at 0.40005 0)
			(size 0 0)
			(layers "F.Cu" "F.Mask" "F.Paste")
			(net "TP_P3V3_E1S_PWRGD_0")
		)
	)
	(footprint ""
		(layer "F.Cu")
		(at 117.86108 -400.414998 90)
		(property "Reference" "R3028"
			(at 0 0 90)
			(layer "F.SilkS")
			(hide yes)
			(effects
				(font
					(size 1.27 1.27)
				)
			)
		)
		(property "Value" ""
			(at 0 0 90)
			(layer "F.Fab")
			(effects
				(font
					(size 1.27 1.27)
				)
			)
		)
		(duplicate_pad_numbers_are_jumpers no)
		(fp_line
			(start 0.7874 -0.4064)
			(end 0.7874 0.4064)
			(stroke
				(width 0.1524)
				(type default)
			)
			(layer "F.SilkS")
		)
		(fp_line
			(start -0.7874 -0.4064)
			(end 0.7874 -0.4064)
			(stroke
				(width 0.1524)
				(type default)
			)
			(layer "F.SilkS")
		)
		(fp_line
			(start 0.7874 0.4064)
			(end -0.7874 0.4064)
			(stroke
				(width 0.1524)
				(type default)
			)
			(layer "F.SilkS")
		)
		(fp_line
			(start -0.7874 0.4064)
			(end -0.7874 -0.4064)
			(stroke
				(width 0.1524)
				(type default)
			)
			(layer "F.SilkS")
		)
		(fp_line
			(start -0.12065 -0.305054)
			(end -0.12065 -0.2794)
			(stroke
				(width 0.1)
				(type default)
			)
			(layer "F.Fab")
		)
		(fp_line
			(start -0.67945 -0.305054)
			(end -0.12065 -0.305054)
			(stroke
				(width 0.1)
				(type default)
			)
			(layer "F.Fab")
		)
		(fp_line
			(start 0.67945 -0.3048)
			(end 0.67945 0.3048)
			(stroke
				(width 0.1)
				(type default)
			)
			(layer "F.Fab")
		)
		(fp_line
			(start 0.12065 -0.3048)
			(end 0.67945 -0.3048)
			(stroke
				(width 0.1)
				(type default)
			)
			(layer "F.Fab")
		)
		(fp_line
			(start 0.12065 -0.2794)
			(end 0.12065 -0.3048)
			(stroke
				(width 0.1)
				(type default)
			)
			(layer "F.Fab")
		)
		(fp_line
			(start -0.12065 -0.2794)
			(end 0.12065 -0.2794)
			(stroke
				(width 0.1)
				(type default)
			)
			(layer "F.Fab")
		)
		(fp_line
			(start 0.120396 0.2794)
			(end -0.12065 0.2794)
			(stroke
				(width 0.1)
				(type default)
			)
			(layer "F.Fab")
		)
		(fp_line
			(start -0.12065 0.2794)
			(end -0.12065 0.3048)
			(stroke
				(width 0.1)
				(type default)
			)
			(layer "F.Fab")
		)
		(fp_line
			(start 0.67945 0.3048)
			(end 0.120396 0.3048)
			(stroke
				(width 0.1)
				(type default)
			)
			(layer "F.Fab")
		)
		(fp_line
			(start 0.120396 0.3048)
			(end 0.120396 0.2794)
			(stroke
				(width 0.1)
				(type default)
			)
			(layer "F.Fab")
		)
		(fp_line
			(start -0.12065 0.3048)
			(end -0.67945 0.3048)
			(stroke
				(width 0.1)
				(type default)
			)
			(layer "F.Fab")
		)
		(fp_line
			(start -0.67945 0.3048)
			(end -0.67945 -0.305054)
			(stroke
				(width 0.1)
				(type default)
			)
			(layer "F.Fab")
		)
		(pad "1" smd circle
			(at -0.40005 0 90)
			(size 0 0)
			(layers "F.Cu" "F.Mask" "F.Paste")
			(net "FM_SMB_1_ALERT_GPU_N")
		)
		(pad "2" smd circle
			(at 0.40005 0 90)
			(size 0 0)
			(layers "F.Cu" "F.Mask" "F.Paste")
			(net "GND")
		)
	)
	(footprint ""
		(layer "F.Cu")
		(at 378.87021 -408.517344 -90)
		(property "Reference" "C874"
			(at 0 0 270)
			(layer "F.SilkS")
			(hide yes)
			(effects
				(font
					(size 1.27 1.27)
				)
			)
		)
		(property "Value" ""
			(at 0 0 270)
			(layer "F.Fab")
			(effects
				(font
					(size 1.27 1.27)
				)
			)
		)
		(duplicate_pad_numbers_are_jumpers no)
		(fp_line
			(start -0.299974 0.150114)
			(end -0.299974 -0.150114)
			(stroke
				(width 0.1)
				(type default)
			)
			(layer "F.Fab")
		)
		(fp_line
			(start 0.299974 0.150114)
			(end -0.299974 0.150114)
			(stroke
				(width 0.1)
				(type default)
			)
			(layer "F.Fab")
		)
		(fp_line
			(start -0.299974 -0.150114)
			(end 0.299974 -0.150114)
			(stroke
				(width 0.1)
				(type default)
			)
			(layer "F.Fab")
		)
		(fp_line
			(start 0.299974 -0.150114)
			(end 0.299974 0.150114)
			(stroke
				(width 0.1)
				(type default)
			)
			(layer "F.Fab")
		)
		(pad "1" smd rect
			(at -0.2667 0 270)
			(size 0.3048 0.381)
			(layers "F.Cu" "F.Mask" "F.Paste")
			(net "P5E_CPU0_PE3_TX_C_DN<13>")
		)
		(pad "2" smd rect
			(at 0.2667 0 270)
			(size 0.3048 0.381)
			(layers "F.Cu" "F.Mask" "F.Paste")
			(net "P5E_CPU0_PE3_TX_DN<13>")
		)
	)
)
